(kicad_pcb
	(version 20241229)
	(generator "pcbnew")
	(generator_version "9.0")
	(general
		(thickness 1.61)
		(legacy_teardrops no)
	)
	(paper "A3")
	(title_block
		(title "SO-DIMM DDR5 Tester")
		(date "2025-11-26")
		(rev "1.3.0")
		(comment 9 "footprints 356-362 of 627")
	)
	(layers
		(0 "F.Cu" signal)
		(4 "In1.Cu" power)
		(6 "In2.Cu" mixed)
		(8 "In3.Cu" power)
		(10 "In4.Cu" mixed)
		(12 "In5.Cu" power)
		(14 "In6.Cu" mixed)
		(16 "In7.Cu" power)
		(18 "In8.Cu" power)
		(20 "In9.Cu" mixed)
		(22 "In10.Cu" power)
		(2 "B.Cu" signal)
		(9 "F.Adhes" user "F.Adhesive")
		(11 "B.Adhes" user "B.Adhesive")
		(13 "F.Paste" user)
		(15 "B.Paste" user)
		(5 "F.SilkS" user "F.Silkscreen")
		(7 "B.SilkS" user "B.Silkscreen")
		(1 "F.Mask" user)
		(3 "B.Mask" user)
		(17 "Dwgs.User" user "User.Drawings")
		(19 "Cmts.User" user "User.Comments")
		(21 "Eco1.User" user "User.Eco1")
		(23 "Eco2.User" user "User.Eco2")
		(25 "Edge.Cuts" user)
		(27 "Margin" user)
		(31 "F.CrtYd" user "F.Courtyard")
		(29 "B.CrtYd" user "B.Courtyard")
		(35 "F.Fab" user)
		(33 "B.Fab" user)
	)
	(footprint "antmicro-footprints:R_0402_1005Metric"
		(layer "B.Cu")
		(at 75.75 140.3 90)
		(descr "Resistor SMD 0402")
		(tags "resistor SMD 0402")
		(property "Reference" "R98"
			(at -1.122484 0.772697 270)
			(layer "B.SilkS")
			(hide yes)
			(effects
				(font
					(size 0.7 0.7)
					(thickness 0.15)
				)
				(justify left bottom mirror)
			)
		)
		(property "Value" "R_220R_0402"
			(at -1.011843 -1.772047 270)
			(layer "B.Fab")
			(effects
				(font
					(size 0.7 0.7)
					(thickness 0.15)
				)
				(justify left bottom mirror)
			)
		)
		(property "Datasheet" "https://www.bourns.com/docs/product-datasheets/cr.pdf"
			(at 0 0 90)
			(layer "F.Fab")
			(hide yes)
			(effects
				(font
					(size 1.27 1.27)
					(thickness 0.15)
				)
			)
		)
		(property "Author" "Antmicro"
			(at 216.05 64.55 0)
			(layer "B.Fab")
			(hide yes)
			(effects
				(font
					(size 1 1)
					(thickness 0.15)
				)
				(justify mirror)
			)
		)
		(property "License" "Apache-2.0"
			(at 216.05 64.55 0)
			(layer "B.Fab")
			(hide yes)
			(effects
				(font
					(size 1 1)
					(thickness 0.15)
				)
				(justify mirror)
			)
		)
		(property "MPN" "CR0402-FX-2200GLF"
			(at 216.05 64.55 0)
			(layer "B.Fab")
			(hide yes)
			(effects
				(font
					(size 1 1)
					(thickness 0.15)
				)
				(justify mirror)
			)
		)
		(property "Manufacturer" "Bourns"
			(at 216.05 64.55 0)
			(layer "B.Fab")
			(hide yes)
			(effects
				(font
					(size 1 1)
					(thickness 0.15)
				)
				(justify mirror)
			)
		)
		(property "Tolerance" "1%"
			(at 216.05 64.55 0)
			(layer "B.Fab")
			(hide yes)
			(effects
				(font
					(size 1 1)
					(thickness 0.15)
				)
				(justify mirror)
			)
		)
		(property "Val" "220R"
			(at 216.05 64.55 0)
			(layer "B.Fab")
			(hide yes)
			(effects
				(font
					(size 1 1)
					(thickness 0.15)
				)
				(justify mirror)
			)
		)
		(sheetname "/Ethernet/")
		(sheetfile "ethernet.kicad_sch")
		(attr smd)
		(fp_rect
			(start -0.93 0.47)
			(end 0.93 -0.47)
			(stroke
				(width 0.05)
				(type solid)
			)
			(fill no)
			(layer "B.CrtYd")
		)
		(fp_rect
			(start -0.5 0.25)
			(end 0.5 -0.25)
			(stroke
				(width 0.15)
				(type solid)
			)
			(fill no)
			(layer "B.Fab")
		)
		(pad "1" smd roundrect
			(at -0.485 0 90)
			(size 0.59 0.64)
			(layers "B.Cu" "B.Mask" "B.Paste")
			(roundrect_rratio 0.25)
			(net 757 "Net-(J6-LED_Y+)")
			(pintype "passive")
		)
		(pad "2" smd roundrect
			(at 0.485 0 90)
			(size 0.59 0.64)
			(layers "B.Cu" "B.Mask" "B.Paste")
			(roundrect_rratio 0.25)
			(net 200 "+3V3")
			(pintype "passive")
		)
	)
	(footprint "antmicro-footprints:R_0402_1005Metric"
		(layer "B.Cu")
		(at 75.770501 133.886 -90)
		(descr "Resistor SMD 0402")
		(tags "resistor SMD 0402")
		(property "Reference" "R99"
			(at -1.122484 0.772697 90)
			(layer "B.SilkS")
			(hide yes)
			(effects
				(font
					(size 0.7 0.7)
					(thickness 0.15)
				)
				(justify left bottom mirror)
			)
		)
		(property "Value" "R_220R_0402"
			(at -1.011843 -1.772047 90)
			(layer "B.Fab")
			(effects
				(font
					(size 0.7 0.7)
					(thickness 0.15)
				)
				(justify left bottom mirror)
			)
		)
		(property "Datasheet" "https://www.bourns.com/docs/product-datasheets/cr.pdf"
			(at 0 0 270)
			(layer "F.Fab")
			(hide yes)
			(effects
				(font
					(size 1.27 1.27)
					(thickness 0.15)
				)
			)
		)
		(property "Author" "Antmicro"
			(at -58.115499 209.656501 0)
			(layer "B.Fab")
			(hide yes)
			(effects
				(font
					(size 1 1)
					(thickness 0.15)
				)
				(justify mirror)
			)
		)
		(property "License" "Apache-2.0"
			(at -58.115499 209.656501 0)
			(layer "B.Fab")
			(hide yes)
			(effects
				(font
					(size 1 1)
					(thickness 0.15)
				)
				(justify mirror)
			)
		)
		(property "MPN" "CR0402-FX-2200GLF"
			(at -58.115499 209.656501 0)
			(layer "B.Fab")
			(hide yes)
			(effects
				(font
					(size 1 1)
					(thickness 0.15)
				)
				(justify mirror)
			)
		)
		(property "Manufacturer" "Bourns"
			(at -58.115499 209.656501 0)
			(layer "B.Fab")
			(hide yes)
			(effects
				(font
					(size 1 1)
					(thickness 0.15)
				)
				(justify mirror)
			)
		)
		(property "Tolerance" "1%"
			(at -58.115499 209.656501 0)
			(layer "B.Fab")
			(hide yes)
			(effects
				(font
					(size 1 1)
					(thickness 0.15)
				)
				(justify mirror)
			)
		)
		(property "Val" "220R"
			(at -58.115499 209.656501 0)
			(layer "B.Fab")
			(hide yes)
			(effects
				(font
					(size 1 1)
					(thickness 0.15)
				)
				(justify mirror)
			)
		)
		(sheetname "/Ethernet/")
		(sheetfile "ethernet.kicad_sch")
		(attr smd)
		(fp_rect
			(start -0.93 0.47)
			(end 0.93 -0.47)
			(stroke
				(width 0.05)
				(type solid)
			)
			(fill no)
			(layer "B.CrtYd")
		)
		(fp_rect
			(start -0.5 0.25)
			(end 0.5 -0.25)
			(stroke
				(width 0.15)
				(type solid)
			)
			(fill no)
			(layer "B.Fab")
		)
		(pad "1" smd roundrect
			(at -0.485 0 270)
			(size 0.59 0.64)
			(layers "B.Cu" "B.Mask" "B.Paste")
			(roundrect_rratio 0.25)
			(net 758 "Net-(J6-LED_G+)")
			(pintype "passive")
		)
		(pad "2" smd roundrect
			(at 0.485 0 270)
			(size 0.59 0.64)
			(layers "B.Cu" "B.Mask" "B.Paste")
			(roundrect_rratio 0.25)
			(net 200 "+3V3")
			(pintype "passive")
		)
	)
	(footprint "antmicro-footprints:R_0402_1005Metric"
		(layer "B.Cu")
		(at 99.525501 163.951 -90)
		(descr "Resistor SMD 0402")
		(tags "resistor SMD 0402")
		(property "Reference" "R113"
			(at -1.122484 0.772697 90)
			(layer "B.SilkS")
			(hide yes)
			(effects
				(font
					(size 0.7 0.7)
					(thickness 0.15)
				)
				(justify left bottom mirror)
			)
		)
		(property "Value" "R_2k2_0402"
			(at -1.011843 -1.772047 90)
			(layer "B.Fab")
			(effects
				(font
					(size 0.7 0.7)
					(thickness 0.15)
				)
				(justify left bottom mirror)
			)
		)
		(property "Datasheet" "https://www.bourns.com/docs/product-datasheets/cr.pdf"
			(at 0 0 270)
			(layer "F.Fab")
			(hide yes)
			(effects
				(font
					(size 1.27 1.27)
					(thickness 0.15)
				)
			)
		)
		(property "Author" "Antmicro"
			(at -64.425499 263.476501 0)
			(layer "B.Fab")
			(hide yes)
			(effects
				(font
					(size 1 1)
					(thickness 0.15)
				)
				(justify mirror)
			)
		)
		(property "License" "Apache-2.0"
			(at -64.425499 263.476501 0)
			(layer "B.Fab")
			(hide yes)
			(effects
				(font
					(size 1 1)
					(thickness 0.15)
				)
				(justify mirror)
			)
		)
		(property "MPN" "CR0402-FX-2201GLF"
			(at -64.425499 263.476501 0)
			(layer "B.Fab")
			(hide yes)
			(effects
				(font
					(size 1 1)
					(thickness 0.15)
				)
				(justify mirror)
			)
		)
		(property "Manufacturer" "Bourns"
			(at -64.425499 263.476501 0)
			(layer "B.Fab")
			(hide yes)
			(effects
				(font
					(size 1 1)
					(thickness 0.15)
				)
				(justify mirror)
			)
		)
		(property "Tolerance" "1%"
			(at -64.425499 263.476501 0)
			(layer "B.Fab")
			(hide yes)
			(effects
				(font
					(size 1 1)
					(thickness 0.15)
				)
				(justify mirror)
			)
		)
		(property "Val" "2k2"
			(at -64.425499 263.476501 0)
			(layer "B.Fab")
			(hide yes)
			(effects
				(font
					(size 1 1)
					(thickness 0.15)
				)
				(justify mirror)
			)
		)
		(sheetname "/Ethernet/")
		(sheetfile "ethernet.kicad_sch")
		(attr smd)
		(fp_rect
			(start -0.93 0.47)
			(end 0.93 -0.47)
			(stroke
				(width 0.05)
				(type solid)
			)
			(fill no)
			(layer "B.CrtYd")
		)
		(fp_rect
			(start -0.5 0.25)
			(end 0.5 -0.25)
			(stroke
				(width 0.15)
				(type solid)
			)
			(fill no)
			(layer "B.Fab")
		)
		(pad "1" smd roundrect
			(at -0.485 0 270)
			(size 0.59 0.64)
			(layers "B.Cu" "B.Mask" "B.Paste")
			(roundrect_rratio 0.25)
			(net 673 "/Ethernet/ETH.RXD0")
			(pintype "passive")
		)
		(pad "2" smd roundrect
			(at 0.485 0 270)
			(size 0.59 0.64)
			(layers "B.Cu" "B.Mask" "B.Paste")
			(roundrect_rratio 0.25)
			(net 1 "GND")
			(pintype "passive")
		)
	)
	(footprint "antmicro-footprints:R_0402_1005Metric"
		(layer "B.Cu")
		(at 98.1 158.1 180)
		(descr "Resistor SMD 0402")
		(tags "resistor SMD 0402")
		(property "Reference" "R110"
			(at -1.122484 0.772697 0)
			(layer "B.SilkS")
			(hide yes)
			(effects
				(font
					(size 0.7 0.7)
					(thickness 0.15)
				)
				(justify left bottom mirror)
			)
		)
		(property "Value" "R_1k_0402"
			(at -1.011843 -1.772047 0)
			(layer "B.Fab")
			(effects
				(font
					(size 0.7 0.7)
					(thickness 0.15)
				)
				(justify left bottom mirror)
			)
		)
		(property "Datasheet" "https://www.bourns.com/docs/product-datasheets/cr.pdf"
			(at 0 0 180)
			(layer "F.Fab")
			(hide yes)
			(effects
				(font
					(size 1.27 1.27)
					(thickness 0.15)
				)
			)
		)
		(property "Author" "Antmicro"
			(at 196.2 316.2 0)
			(layer "B.Fab")
			(hide yes)
			(effects
				(font
					(size 1 1)
					(thickness 0.15)
				)
				(justify mirror)
			)
		)
		(property "License" "Apache-2.0"
			(at 196.2 316.2 0)
			(layer "B.Fab")
			(hide yes)
			(effects
				(font
					(size 1 1)
					(thickness 0.15)
				)
				(justify mirror)
			)
		)
		(property "MPN" "CR0402-FX-1001GLF"
			(at 196.2 316.2 0)
			(layer "B.Fab")
			(hide yes)
			(effects
				(font
					(size 1 1)
					(thickness 0.15)
				)
				(justify mirror)
			)
		)
		(property "Manufacturer" "Bourns"
			(at 196.2 316.2 0)
			(layer "B.Fab")
			(hide yes)
			(effects
				(font
					(size 1 1)
					(thickness 0.15)
				)
				(justify mirror)
			)
		)
		(property "Tolerance" "1%"
			(at 196.2 316.2 0)
			(layer "B.Fab")
			(hide yes)
			(effects
				(font
					(size 1 1)
					(thickness 0.15)
				)
				(justify mirror)
			)
		)
		(property "Val" "1k"
			(at 196.2 316.2 0)
			(layer "B.Fab")
			(hide yes)
			(effects
				(font
					(size 1 1)
					(thickness 0.15)
				)
				(justify mirror)
			)
		)
		(sheetname "/Ethernet/")
		(sheetfile "ethernet.kicad_sch")
		(attr smd)
		(fp_rect
			(start -0.93 0.47)
			(end 0.93 -0.47)
			(stroke
				(width 0.05)
				(type solid)
			)
			(fill no)
			(layer "B.CrtYd")
		)
		(fp_rect
			(start -0.5 0.25)
			(end 0.5 -0.25)
			(stroke
				(width 0.15)
				(type solid)
			)
			(fill no)
			(layer "B.Fab")
		)
		(pad "1" smd roundrect
			(at -0.485 0 180)
			(size 0.59 0.64)
			(layers "B.Cu" "B.Mask" "B.Paste")
			(roundrect_rratio 0.25)
			(net 680 "/Ethernet/ETH.MDIO")
			(pintype "passive")
		)
		(pad "2" smd roundrect
			(at 0.485 0 180)
			(size 0.59 0.64)
			(layers "B.Cu" "B.Mask" "B.Paste")
			(roundrect_rratio 0.25)
			(net 200 "+3V3")
			(pintype "passive")
		)
	)
	(footprint "antmicro-footprints:R_0402_1005Metric"
		(layer "B.Cu")
		(at 97.425501 163.951 -90)
		(descr "Resistor SMD 0402")
		(tags "resistor SMD 0402")
		(property "Reference" "R115"
			(at -1.122484 0.772697 90)
			(layer "B.SilkS")
			(hide yes)
			(effects
				(font
					(size 0.7 0.7)
					(thickness 0.15)
				)
				(justify left bottom mirror)
			)
		)
		(property "Value" "R_2k2_0402"
			(at -1.011843 -1.772047 90)
			(layer "B.Fab")
			(effects
				(font
					(size 0.7 0.7)
					(thickness 0.15)
				)
				(justify left bottom mirror)
			)
		)
		(property "Datasheet" "https://www.bourns.com/docs/product-datasheets/cr.pdf"
			(at 0 0 270)
			(layer "F.Fab")
			(hide yes)
			(effects
				(font
					(size 1.27 1.27)
					(thickness 0.15)
				)
			)
		)
		(property "Author" "Antmicro"
			(at -66.525499 261.376501 0)
			(layer "B.Fab")
			(hide yes)
			(effects
				(font
					(size 1 1)
					(thickness 0.15)
				)
				(justify mirror)
			)
		)
		(property "License" "Apache-2.0"
			(at -66.525499 261.376501 0)
			(layer "B.Fab")
			(hide yes)
			(effects
				(font
					(size 1 1)
					(thickness 0.15)
				)
				(justify mirror)
			)
		)
		(property "MPN" "CR0402-FX-2201GLF"
			(at -66.525499 261.376501 0)
			(layer "B.Fab")
			(hide yes)
			(effects
				(font
					(size 1 1)
					(thickness 0.15)
				)
				(justify mirror)
			)
		)
		(property "Manufacturer" "Bourns"
			(at -66.525499 261.376501 0)
			(layer "B.Fab")
			(hide yes)
			(effects
				(font
					(size 1 1)
					(thickness 0.15)
				)
				(justify mirror)
			)
		)
		(property "Tolerance" "1%"
			(at -66.525499 261.376501 0)
			(layer "B.Fab")
			(hide yes)
			(effects
				(font
					(size 1 1)
					(thickness 0.15)
				)
				(justify mirror)
			)
		)
		(property "Val" "2k2"
			(at -66.525499 261.376501 0)
			(layer "B.Fab")
			(hide yes)
			(effects
				(font
					(size 1 1)
					(thickness 0.15)
				)
				(justify mirror)
			)
		)
		(sheetname "/Ethernet/")
		(sheetfile "ethernet.kicad_sch")
		(attr exclude_from_pos_files exclude_from_bom dnp)
		(fp_rect
			(start -0.93 0.47)
			(end 0.93 -0.47)
			(stroke
				(width 0.05)
				(type solid)
			)
			(fill no)
			(layer "B.CrtYd")
		)
		(fp_rect
			(start -0.5 0.25)
			(end 0.5 -0.25)
			(stroke
				(width 0.15)
				(type solid)
			)
			(fill no)
			(layer "B.Fab")
		)
		(pad "1" smd roundrect
			(at -0.485 0 270)
			(size 0.59 0.64)
			(layers "B.Cu" "B.Mask" "B.Paste")
			(roundrect_rratio 0.25)
			(net 675 "/Ethernet/ETH.RXD2")
			(pintype "passive")
		)
		(pad "2" smd roundrect
			(at 0.485 0 270)
			(size 0.59 0.64)
			(layers "B.Cu" "B.Mask" "B.Paste")
			(roundrect_rratio 0.25)
			(net 1 "GND")
			(pintype "passive")
		)
	)
	(footprint "antmicro-footprints:R_0402_1005Metric"
		(layer "B.Cu")
		(at 101.625501 163.951 -90)
		(descr "Resistor SMD 0402")
		(tags "resistor SMD 0402")
		(property "Reference" "R117"
			(at -1.122484 0.772697 90)
			(layer "B.SilkS")
			(hide yes)
			(effects
				(font
					(size 0.7 0.7)
					(thickness 0.15)
				)
				(justify left bottom mirror)
			)
		)
		(property "Value" "R_2k2_0402"
			(at -1.011843 -1.772047 90)
			(layer "B.Fab")
			(effects
				(font
					(size 0.7 0.7)
					(thickness 0.15)
				)
				(justify left bottom mirror)
			)
		)
		(property "Datasheet" "https://www.bourns.com/docs/product-datasheets/cr.pdf"
			(at 0 0 270)
			(layer "F.Fab")
			(hide yes)
			(effects
				(font
					(size 1.27 1.27)
					(thickness 0.15)
				)
			)
		)
		(property "Author" "Antmicro"
			(at -62.325499 265.576501 0)
			(layer "B.Fab")
			(hide yes)
			(effects
				(font
					(size 1 1)
					(thickness 0.15)
				)
				(justify mirror)
			)
		)
		(property "License" "Apache-2.0"
			(at -62.325499 265.576501 0)
			(layer "B.Fab")
			(hide yes)
			(effects
				(font
					(size 1 1)
					(thickness 0.15)
				)
				(justify mirror)
			)
		)
		(property "MPN" "CR0402-FX-2201GLF"
			(at -62.325499 265.576501 0)
			(layer "B.Fab")
			(hide yes)
			(effects
				(font
					(size 1 1)
					(thickness 0.15)
				)
				(justify mirror)
			)
		)
		(property "Manufacturer" "Bourns"
			(at -62.325499 265.576501 0)
			(layer "B.Fab")
			(hide yes)
			(effects
				(font
					(size 1 1)
					(thickness 0.15)
				)
				(justify mirror)
			)
		)
		(property "Tolerance" "1%"
			(at -62.325499 265.576501 0)
			(layer "B.Fab")
			(hide yes)
			(effects
				(font
					(size 1 1)
					(thickness 0.15)
				)
				(justify mirror)
			)
		)
		(property "Val" "2k2"
			(at -62.325499 265.576501 0)
			(layer "B.Fab")
			(hide yes)
			(effects
				(font
					(size 1 1)
					(thickness 0.15)
				)
				(justify mirror)
			)
		)
		(sheetname "/Ethernet/")
		(sheetfile "ethernet.kicad_sch")
		(attr smd)
		(fp_rect
			(start -0.93 0.47)
			(end 0.93 -0.47)
			(stroke
				(width 0.05)
				(type solid)
			)
			(fill no)
			(layer "B.CrtYd")
		)
		(fp_rect
			(start -0.5 0.25)
			(end 0.5 -0.25)
			(stroke
				(width 0.15)
				(type solid)
			)
			(fill no)
			(layer "B.Fab")
		)
		(pad "1" smd roundrect
			(at -0.485 0 270)
			(size 0.59 0.64)
			(layers "B.Cu" "B.Mask" "B.Paste")
			(roundrect_rratio 0.25)
			(net 677 "/Ethernet/ETH.RX_CTL")
			(pintype "passive")
		)
		(pad "2" smd roundrect
			(at 0.485 0 270)
			(size 0.59 0.64)
			(layers "B.Cu" "B.Mask" "B.Paste")
			(roundrect_rratio 0.25)
			(net 1 "GND")
			(pintype "passive")
		)
	)
	(footprint "antmicro-footprints:R_0402_1005Metric"
		(layer "B.Cu")
		(at 100.550501 163.951 -90)
		(descr "Resistor SMD 0402")
		(tags "resistor SMD 0402")
		(property "Reference" "R118"
			(at -1.122484 0.772697 90)
			(layer "B.SilkS")
			(hide yes)
			(effects
				(font
					(size 0.7 0.7)
					(thickness 0.15)
				)
				(justify left bottom mirror)
			)
		)
		(property "Value" "R_2k2_0402"
			(at -1.011843 -1.772047 90)
			(layer "B.Fab")
			(effects
				(font
					(size 0.7 0.7)
					(thickness 0.15)
				)
				(justify left bottom mirror)
			)
		)
		(property "Datasheet" "https://www.bourns.com/docs/product-datasheets/cr.pdf"
			(at 0 0 270)
			(layer "F.Fab")
			(hide yes)
			(effects
				(font
					(size 1.27 1.27)
					(thickness 0.15)
				)
			)
		)
		(property "Author" "Antmicro"
			(at -63.400499 264.501501 0)
			(layer "B.Fab")
			(hide yes)
			(effects
				(font
					(size 1 1)
					(thickness 0.15)
				)
				(justify mirror)
			)
		)
		(property "License" "Apache-2.0"
			(at -63.400499 264.501501 0)
			(layer "B.Fab")
			(hide yes)
			(effects
				(font
					(size 1 1)
					(thickness 0.15)
				)
				(justify mirror)
			)
		)
		(property "MPN" "CR0402-FX-2201GLF"
			(at -63.400499 264.501501 0)
			(layer "B.Fab")
			(hide yes)
			(effects
				(font
					(size 1 1)
					(thickness 0.15)
				)
				(justify mirror)
			)
		)
		(property "Manufacturer" "Bourns"
			(at -63.400499 264.501501 0)
			(layer "B.Fab")
			(hide yes)
			(effects
				(font
					(size 1 1)
					(thickness 0.15)
				)
				(justify mirror)
			)
		)
		(property "Tolerance" "1%"
			(at -63.400499 264.501501 0)
			(layer "B.Fab")
			(hide yes)
			(effects
				(font
					(size 1 1)
					(thickness 0.15)
				)
				(justify mirror)
			)
		)
		(property "Val" "2k2"
			(at -63.400499 264.501501 0)
			(layer "B.Fab")
			(hide yes)
			(effects
				(font
					(size 1 1)
					(thickness 0.15)
				)
				(justify mirror)
			)
		)
		(sheetname "/Ethernet/")
		(sheetfile "ethernet.kicad_sch")
		(attr smd)
		(fp_rect
			(start -0.93 0.47)
			(end 0.93 -0.47)
			(stroke
				(width 0.05)
				(type solid)
			)
			(fill no)
			(layer "B.CrtYd")
		)
		(fp_rect
			(start -0.5 0.25)
			(end 0.5 -0.25)
			(stroke
				(width 0.15)
				(type solid)
			)
			(fill no)
			(layer "B.Fab")
		)
		(pad "1" smd roundrect
			(at -0.485 0 270)
			(size 0.59 0.64)
			(layers "B.Cu" "B.Mask" "B.Paste")
			(roundrect_rratio 0.25)
			(net 678 "/Ethernet/ETH.RXC")
			(pintype "passive")
		)
		(pad "2" smd roundrect
			(at 0.485 0 270)
			(size 0.59 0.64)
			(layers "B.Cu" "B.Mask" "B.Paste")
			(roundrect_rratio 0.25)
			(net 1 "GND")
			(pintype "passive")
		)
	)
)
